(kicad_pcb
	(version 20260206)
	(generator "pcbnew")
	(generator_version "10.0")
	(general
		(thickness 1.6)
		(legacy_teardrops no)
	)
	(paper "A4")
	(title_block
		(title "04192023_DAF0TMB3IC0_F0TG_MB_C_brd_V02_OCP.brd")
		(comment 1 "Grand Teton / footprints 198-206 of 8354")
	)
	(layers
		(0 "F.Cu" signal "TOP")
		(4 "In1.Cu" signal "GND")
		(6 "In2.Cu" signal "IN1")
		(8 "In3.Cu" signal "GND1")
		(10 "In4.Cu" signal "IN2")
		(12 "In5.Cu" signal "GND2")
		(14 "In6.Cu" signal "IN3")
		(16 "In7.Cu" signal "GND3")
		(18 "In8.Cu" signal "VCC")
		(20 "In9.Cu" signal "VCC1")
		(22 "In10.Cu" signal "GND4")
		(24 "In11.Cu" signal "IN4")
		(26 "In12.Cu" signal "GND5")
		(28 "In13.Cu" signal "IN5")
		(30 "In14.Cu" signal "GND6")
		(32 "In15.Cu" signal "IN6")
		(34 "In16.Cu" signal "GND7")
		(2 "B.Cu" signal "BOTTOM")
		(9 "F.Adhes" user "F.Adhesive")
		(11 "B.Adhes" user "B.Adhesive")
		(13 "F.Paste" user "Package Geometry/Pastemask Top")
		(15 "B.Paste" user "Package Geometry/Pastemask Bottom")
		(5 "F.SilkS" user "Ref Des/Silkscreen Top")
		(7 "B.SilkS" user "Ref Des/Silkscreen Bottom")
		(1 "F.Mask" user "Board Geometry/Soldermask Top")
		(3 "B.Mask" user "Board Geometry/Soldermask Bottom")
		(17 "Dwgs.User" user "User.Drawings")
		(19 "Cmts.User" user "User.Comments")
		(21 "Eco1.User" user "User.Eco1")
		(23 "Eco2.User" user "User.Eco2")
		(25 "Edge.Cuts" user "Board Geometry/Outline")
		(27 "Margin" user)
		(31 "F.CrtYd" user "Package Geometry/Place Bound Top")
		(29 "B.CrtYd" user "Package Geometry/Place Bound Bottom")
		(35 "F.Fab" user "Ref Des/Assembly Top")
		(33 "B.Fab" user "Ref Des/Assembly Bottom")
	)
	(footprint ""
		(layer "F.Cu")
		(at 103.453946 -54.882034 -90)
		(property "Reference" "R6320"
			(at 0 0 270)
			(layer "F.SilkS")
			(hide yes)
			(effects
				(font
					(size 1.27 1.27)
				)
			)
		)
		(property "Value" ""
			(at 0 0 270)
			(layer "F.Fab")
			(effects
				(font
					(size 1.27 1.27)
				)
			)
		)
		(duplicate_pad_numbers_are_jumpers no)
		(fp_line
			(start -0.7874 0.4064)
			(end -0.7874 -0.4064)
			(stroke
				(width 0.1524)
				(type default)
			)
			(layer "F.SilkS")
		)
		(fp_line
			(start 0.7874 0.4064)
			(end -0.7874 0.4064)
			(stroke
				(width 0.1524)
				(type default)
			)
			(layer "F.SilkS")
		)
		(fp_line
			(start -0.7874 -0.4064)
			(end 0.7874 -0.4064)
			(stroke
				(width 0.1524)
				(type default)
			)
			(layer "F.SilkS")
		)
		(fp_line
			(start 0.7874 -0.4064)
			(end 0.7874 0.4064)
			(stroke
				(width 0.1524)
				(type default)
			)
			(layer "F.SilkS")
		)
		(fp_line
			(start -0.67945 0.3048)
			(end -0.67945 -0.305054)
			(stroke
				(width 0.1)
				(type default)
			)
			(layer "F.Fab")
		)
		(fp_line
			(start -0.12065 0.3048)
			(end -0.67945 0.3048)
			(stroke
				(width 0.1)
				(type default)
			)
			(layer "F.Fab")
		)
		(fp_line
			(start 0.120396 0.3048)
			(end 0.120396 0.2794)
			(stroke
				(width 0.1)
				(type default)
			)
			(layer "F.Fab")
		)
		(fp_line
			(start 0.67945 0.3048)
			(end 0.120396 0.3048)
			(stroke
				(width 0.1)
				(type default)
			)
			(layer "F.Fab")
		)
		(fp_line
			(start -0.12065 0.2794)
			(end -0.12065 0.3048)
			(stroke
				(width 0.1)
				(type default)
			)
			(layer "F.Fab")
		)
		(fp_line
			(start 0.120396 0.2794)
			(end -0.12065 0.2794)
			(stroke
				(width 0.1)
				(type default)
			)
			(layer "F.Fab")
		)
		(fp_line
			(start -0.12065 -0.2794)
			(end 0.12065 -0.2794)
			(stroke
				(width 0.1)
				(type default)
			)
			(layer "F.Fab")
		)
		(fp_line
			(start 0.12065 -0.2794)
			(end 0.12065 -0.3048)
			(stroke
				(width 0.1)
				(type default)
			)
			(layer "F.Fab")
		)
		(fp_line
			(start 0.12065 -0.3048)
			(end 0.67945 -0.3048)
			(stroke
				(width 0.1)
				(type default)
			)
			(layer "F.Fab")
		)
		(fp_line
			(start 0.67945 -0.3048)
			(end 0.67945 0.3048)
			(stroke
				(width 0.1)
				(type default)
			)
			(layer "F.Fab")
		)
		(fp_line
			(start -0.67945 -0.305054)
			(end -0.12065 -0.305054)
			(stroke
				(width 0.1)
				(type default)
			)
			(layer "F.Fab")
		)
		(fp_line
			(start -0.12065 -0.305054)
			(end -0.12065 -0.2794)
			(stroke
				(width 0.1)
				(type default)
			)
			(layer "F.Fab")
		)
		(pad "1" smd circle
			(at -0.40005 0 270)
			(size 0 0)
			(layers "F.Cu" "F.Mask" "F.Paste")
			(net "P3V3_AUX")
		)
		(pad "2" smd circle
			(at 0.40005 0 270)
			(size 0 0)
			(layers "F.Cu" "F.Mask" "F.Paste")
			(net "USB_HUB2_MRP_RESET_N")
		)
	)
	(footprint ""
		(layer "F.Cu")
		(at 174.030894 -391.34288 180)
		(property "Reference" "R865"
			(at 0 0 180)
			(layer "F.SilkS")
			(hide yes)
			(effects
				(font
					(size 1.27 1.27)
				)
			)
		)
		(property "Value" ""
			(at 0 0 180)
			(layer "F.Fab")
			(effects
				(font
					(size 1.27 1.27)
				)
			)
		)
		(duplicate_pad_numbers_are_jumpers no)
		(fp_line
			(start 0.32512 0.175006)
			(end -0.32512 0.175006)
			(stroke
				(width 0.1)
				(type default)
			)
			(layer "F.Fab")
		)
		(fp_line
			(start 0.32512 -0.175006)
			(end 0.32512 0.175006)
			(stroke
				(width 0.1)
				(type default)
			)
			(layer "F.Fab")
		)
		(fp_line
			(start -0.32512 0.175006)
			(end -0.32512 -0.175006)
			(stroke
				(width 0.1)
				(type default)
			)
			(layer "F.Fab")
		)
		(fp_line
			(start -0.32512 -0.175006)
			(end 0.32512 -0.175006)
			(stroke
				(width 0.1)
				(type default)
			)
			(layer "F.Fab")
		)
		(pad "1" smd rect
			(at -0.2667 0 180)
			(size 0.3048 0.381)
			(layers "F.Cu" "F.Mask" "F.Paste")
			(net "RT_CPU1_P2_ADDR2")
		)
		(pad "2" smd rect
			(at 0.2667 0)
			(size 0.3048 0.381)
			(layers "F.Cu" "F.Mask" "F.Paste")
			(net "GND")
		)
	)
	(footprint ""
		(layer "F.Cu")
		(at 306.388516 -438.476644 90)
		(property "Reference" "R4576"
			(at 0 0 90)
			(layer "F.SilkS")
			(hide yes)
			(effects
				(font
					(size 1.27 1.27)
				)
			)
		)
		(property "Value" ""
			(at 0 0 90)
			(layer "F.Fab")
			(effects
				(font
					(size 1.27 1.27)
				)
			)
		)
		(duplicate_pad_numbers_are_jumpers no)
		(fp_line
			(start 0.7874 -0.4064)
			(end 0.7874 0.4064)
			(stroke
				(width 0.1524)
				(type default)
			)
			(layer "F.SilkS")
		)
		(fp_line
			(start -0.7874 -0.4064)
			(end 0.7874 -0.4064)
			(stroke
				(width 0.1524)
				(type default)
			)
			(layer "F.SilkS")
		)
		(fp_line
			(start 0.7874 0.4064)
			(end -0.7874 0.4064)
			(stroke
				(width 0.1524)
				(type default)
			)
			(layer "F.SilkS")
		)
		(fp_line
			(start -0.7874 0.4064)
			(end -0.7874 -0.4064)
			(stroke
				(width 0.1524)
				(type default)
			)
			(layer "F.SilkS")
		)
		(fp_line
			(start -0.12065 -0.305054)
			(end -0.12065 -0.2794)
			(stroke
				(width 0.1)
				(type default)
			)
			(layer "F.Fab")
		)
		(fp_line
			(start -0.67945 -0.305054)
			(end -0.12065 -0.305054)
			(stroke
				(width 0.1)
				(type default)
			)
			(layer "F.Fab")
		)
		(fp_line
			(start 0.67945 -0.3048)
			(end 0.67945 0.3048)
			(stroke
				(width 0.1)
				(type default)
			)
			(layer "F.Fab")
		)
		(fp_line
			(start 0.12065 -0.3048)
			(end 0.67945 -0.3048)
			(stroke
				(width 0.1)
				(type default)
			)
			(layer "F.Fab")
		)
		(fp_line
			(start 0.12065 -0.2794)
			(end 0.12065 -0.3048)
			(stroke
				(width 0.1)
				(type default)
			)
			(layer "F.Fab")
		)
		(fp_line
			(start -0.12065 -0.2794)
			(end 0.12065 -0.2794)
			(stroke
				(width 0.1)
				(type default)
			)
			(layer "F.Fab")
		)
		(fp_line
			(start 0.120396 0.2794)
			(end -0.12065 0.2794)
			(stroke
				(width 0.1)
				(type default)
			)
			(layer "F.Fab")
		)
		(fp_line
			(start -0.12065 0.2794)
			(end -0.12065 0.3048)
			(stroke
				(width 0.1)
				(type default)
			)
			(layer "F.Fab")
		)
		(fp_line
			(start 0.67945 0.3048)
			(end 0.120396 0.3048)
			(stroke
				(width 0.1)
				(type default)
			)
			(layer "F.Fab")
		)
		(fp_line
			(start 0.120396 0.3048)
			(end 0.120396 0.2794)
			(stroke
				(width 0.1)
				(type default)
			)
			(layer "F.Fab")
		)
		(fp_line
			(start -0.12065 0.3048)
			(end -0.67945 0.3048)
			(stroke
				(width 0.1)
				(type default)
			)
			(layer "F.Fab")
		)
		(fp_line
			(start -0.67945 0.3048)
			(end -0.67945 -0.305054)
			(stroke
				(width 0.1)
				(type default)
			)
			(layer "F.Fab")
		)
		(pad "1" smd circle
			(at -0.40005 0 90)
			(size 0 0)
			(layers "F.Cu" "F.Mask" "F.Paste")
			(net "GPU_3V3IO_RSVD5_FFU")
		)
		(pad "2" smd circle
			(at 0.40005 0 90)
			(size 0 0)
			(layers "F.Cu" "F.Mask" "F.Paste")
			(net "GPU_3V3IO_RSVD5_FFU_ISO")
		)
	)
	(footprint ""
		(layer "F.Cu")
		(at 33.865058 -173.55566)
		(property "Reference" "R1335"
			(at 0 0 0)
			(layer "F.SilkS")
			(hide yes)
			(effects
				(font
					(size 1.27 1.27)
				)
			)
		)
		(property "Value" ""
			(at 0 0 0)
			(layer "F.Fab")
			(effects
				(font
					(size 1.27 1.27)
				)
			)
		)
		(duplicate_pad_numbers_are_jumpers no)
		(fp_line
			(start -0.7874 -0.4064)
			(end 0.7874 -0.4064)
			(stroke
				(width 0.1524)
				(type default)
			)
			(layer "F.SilkS")
		)
		(fp_line
			(start -0.7874 0.4064)
			(end -0.7874 -0.4064)
			(stroke
				(width 0.1524)
				(type default)
			)
			(layer "F.SilkS")
		)
		(fp_line
			(start 0.7874 -0.4064)
			(end 0.7874 0.4064)
			(stroke
				(width 0.1524)
				(type default)
			)
			(layer "F.SilkS")
		)
		(fp_line
			(start 0.7874 0.4064)
			(end -0.7874 0.4064)
			(stroke
				(width 0.1524)
				(type default)
			)
			(layer "F.SilkS")
		)
		(fp_line
			(start -0.67945 -0.305054)
			(end -0.12065 -0.305054)
			(stroke
				(width 0.1)
				(type default)
			)
			(layer "F.Fab")
		)
		(fp_line
			(start -0.67945 0.3048)
			(end -0.67945 -0.305054)
			(stroke
				(width 0.1)
				(type default)
			)
			(layer "F.Fab")
		)
		(fp_line
			(start -0.12065 -0.305054)
			(end -0.12065 -0.2794)
			(stroke
				(width 0.1)
				(type default)
			)
			(layer "F.Fab")
		)
		(fp_line
			(start -0.12065 -0.2794)
			(end 0.12065 -0.2794)
			(stroke
				(width 0.1)
				(type default)
			)
			(layer "F.Fab")
		)
		(fp_line
			(start -0.12065 0.2794)
			(end -0.12065 0.3048)
			(stroke
				(width 0.1)
				(type default)
			)
			(layer "F.Fab")
		)
		(fp_line
			(start -0.12065 0.3048)
			(end -0.67945 0.3048)
			(stroke
				(width 0.1)
				(type default)
			)
			(layer "F.Fab")
		)
		(fp_line
			(start 0.120396 0.2794)
			(end -0.12065 0.2794)
			(stroke
				(width 0.1)
				(type default)
			)
			(layer "F.Fab")
		)
		(fp_line
			(start 0.120396 0.3048)
			(end 0.120396 0.2794)
			(stroke
				(width 0.1)
				(type default)
			)
			(layer "F.Fab")
		)
		(fp_line
			(start 0.12065 -0.3048)
			(end 0.67945 -0.3048)
			(stroke
				(width 0.1)
				(type default)
			)
			(layer "F.Fab")
		)
		(fp_line
			(start 0.12065 -0.2794)
			(end 0.12065 -0.3048)
			(stroke
				(width 0.1)
				(type default)
			)
			(layer "F.Fab")
		)
		(fp_line
			(start 0.67945 -0.3048)
			(end 0.67945 0.3048)
			(stroke
				(width 0.1)
				(type default)
			)
			(layer "F.Fab")
		)
		(fp_line
			(start 0.67945 0.3048)
			(end 0.120396 0.3048)
			(stroke
				(width 0.1)
				(type default)
			)
			(layer "F.Fab")
		)
		(pad "1" smd rect
			(at -0.40005 0 180)
			(size 0.4572 0.508)
			(layers "F.Cu" "F.Mask" "F.Paste")
			(net "I3C_SPD_DDRAF_CPU1_BYPASS_SDA")
		)
		(pad "2" smd rect
			(at 0.40005 0 180)
			(size 0.4572 0.508)
			(layers "F.Cu" "F.Mask" "F.Paste")
			(net "I3C_SPD_DDRAF_CPU1_SDA")
		)
	)
	(footprint ""
		(layer "F.Cu")
		(at 339.70976 -15.924276 90)
		(property "Reference" "D5"
			(at -2.9718 -0.079248 90)
			(unlocked yes)
			(layer "F.SilkS")
			(effects
				(font
					(size 0.7874 0.5842)
					(thickness 0.1524)
				)
				(justify left)
			)
		)
		(property "Value" ""
			(at 0 0 90)
			(layer "F.Fab")
			(effects
				(font
					(size 1.27 1.27)
				)
			)
		)
		(duplicate_pad_numbers_are_jumpers no)
		(fp_line
			(start 1.16078 -0.4826)
			(end 1.16078 0.4826)
			(stroke
				(width 0.1524)
				(type default)
			)
			(layer "F.SilkS")
		)
		(fp_line
			(start 1.03378 -0.4826)
			(end 1.03378 0.4826)
			(stroke
				(width 0.1524)
				(type default)
			)
			(layer "F.SilkS")
		)
		(fp_line
			(start 0.90678 -0.4826)
			(end 0.90678 0.4826)
			(stroke
				(width 0.1524)
				(type default)
			)
			(layer "F.SilkS")
		)
		(fp_line
			(start -0.64008 -0.4826)
			(end 1.16078 -0.4826)
			(stroke
				(width 0.1524)
				(type default)
			)
			(layer "F.SilkS")
		)
		(fp_line
			(start -0.79248 -0.4826)
			(end 1.03378 -0.4826)
			(stroke
				(width 0.1524)
				(type default)
			)
			(layer "F.SilkS")
		)
		(fp_line
			(start -0.89408 -0.4826)
			(end 0.90678 -0.4826)
			(stroke
				(width 0.1524)
				(type default)
			)
			(layer "F.SilkS")
		)
		(fp_line
			(start 1.16078 0.4826)
			(end -0.64008 0.4826)
			(stroke
				(width 0.1524)
				(type default)
			)
			(layer "F.SilkS")
		)
		(fp_line
			(start 1.03378 0.4826)
			(end -0.79248 0.4826)
			(stroke
				(width 0.1524)
				(type default)
			)
			(layer "F.SilkS")
		)
		(fp_line
			(start 0.90678 0.4826)
			(end -0.90678 0.4826)
			(stroke
				(width 0.1524)
				(type default)
			)
			(layer "F.SilkS")
		)
		(fp_line
			(start -0.90678 0.4826)
			(end -0.90678 -0.4699)
			(stroke
				(width 0.1524)
				(type default)
			)
			(layer "F.SilkS")
		)
		(fp_line
			(start 0.499872 -0.249936)
			(end 0.499872 0.249936)
			(stroke
				(width 0.1)
				(type default)
			)
			(layer "F.Fab")
		)
		(fp_line
			(start -0.499872 -0.249936)
			(end 0.499872 -0.249936)
			(stroke
				(width 0.1)
				(type default)
			)
			(layer "F.Fab")
		)
		(fp_line
			(start 0.499872 0.249936)
			(end -0.499872 0.249936)
			(stroke
				(width 0.1)
				(type default)
			)
			(layer "F.Fab")
		)
		(fp_line
			(start -0.499872 0.249936)
			(end -0.499872 -0.249936)
			(stroke
				(width 0.1)
				(type default)
			)
			(layer "F.Fab")
		)
		(pad "A" smd rect
			(at -0.47498 0 90)
			(size 0.6096 0.7112)
			(layers "F.Cu" "F.Mask" "F.Paste")
			(net "PU_BOOT_RDY_LED")
		)
		(pad "C" smd rect
			(at 0.47498 0 90)
			(size 0.6096 0.7112)
			(layers "F.Cu" "F.Mask" "F.Paste")
			(net "BOOT_RDY_LED_N")
		)
	)
	(footprint ""
		(layer "F.Cu")
		(at 303.69383 -153.917142 180)
		(property "Reference" "TP9"
			(at 2.88544 -0.005334 0)
			(unlocked yes)
			(layer "F.SilkS")
			(effects
				(font
					(size 0.7874 0.5842)
					(thickness 0.1524)
				)
				(justify left)
			)
		)
		(property "Value" ""
			(at 0 0 180)
			(layer "F.Fab")
			(effects
				(font
					(size 1.27 1.27)
				)
			)
		)
		(duplicate_pad_numbers_are_jumpers no)
		(pad "1" smd circle
			(at 0 0 180)
			(size 0.762 0.762)
			(layers "F.Cu" "F.Mask" "F.Paste")
			(net "VSENSE_PVDD18_S5_P0_DP")
		)
	)
	(footprint ""
		(layer "F.Cu")
		(at 344.344244 -383.88163 -90)
		(property "Reference" "C950"
			(at 0 0 270)
			(layer "F.SilkS")
			(hide yes)
			(effects
				(font
					(size 1.27 1.27)
				)
			)
		)
		(property "Value" ""
			(at 0 0 270)
			(layer "F.Fab")
			(effects
				(font
					(size 1.27 1.27)
				)
			)
		)
		(duplicate_pad_numbers_are_jumpers no)
		(fp_line
			(start -0.299974 0.150114)
			(end -0.299974 -0.150114)
			(stroke
				(width 0.1)
				(type default)
			)
			(layer "F.Fab")
		)
		(fp_line
			(start 0.299974 0.150114)
			(end -0.299974 0.150114)
			(stroke
				(width 0.1)
				(type default)
			)
			(layer "F.Fab")
		)
		(fp_line
			(start -0.299974 -0.150114)
			(end 0.299974 -0.150114)
			(stroke
				(width 0.1)
				(type default)
			)
			(layer "F.Fab")
		)
		(fp_line
			(start 0.299974 -0.150114)
			(end 0.299974 0.150114)
			(stroke
				(width 0.1)
				(type default)
			)
			(layer "F.Fab")
		)
		(pad "1" smd rect
			(at -0.2667 0 270)
			(size 0.3048 0.381)
			(layers "F.Cu" "F.Mask" "F.Paste")
			(net "P5E_CPU0_P1_TX_C_DN<7>")
		)
		(pad "2" smd rect
			(at 0.2667 0 270)
			(size 0.3048 0.381)
			(layers "F.Cu" "F.Mask" "F.Paste")
			(net "P5E_CPU0_P1_TX_DN<7>")
		)
	)
	(footprint ""
		(layer "F.Cu")
		(at 398.595088 -389.86206 180)
		(property "Reference" "C868"
			(at 0 0 180)
			(layer "F.SilkS")
			(hide yes)
			(effects
				(font
					(size 1.27 1.27)
				)
			)
		)
		(property "Value" ""
			(at 0 0 180)
			(layer "F.Fab")
			(effects
				(font
					(size 1.27 1.27)
				)
			)
		)
		(duplicate_pad_numbers_are_jumpers no)
		(fp_line
			(start 0.299974 0.150114)
			(end -0.299974 0.150114)
			(stroke
				(width 0.1)
				(type default)
			)
			(layer "F.Fab")
		)
		(fp_line
			(start 0.299974 -0.150114)
			(end 0.299974 0.150114)
			(stroke
				(width 0.1)
				(type default)
			)
			(layer "F.Fab")
		)
		(fp_line
			(start -0.299974 0.150114)
			(end -0.299974 -0.150114)
			(stroke
				(width 0.1)
				(type default)
			)
			(layer "F.Fab")
		)
		(fp_line
			(start -0.299974 -0.150114)
			(end 0.299974 -0.150114)
			(stroke
				(width 0.1)
				(type default)
			)
			(layer "F.Fab")
		)
		(pad "1" smd rect
			(at -0.2667 0 180)
			(size 0.3048 0.381)
			(layers "F.Cu" "F.Mask" "F.Paste")
			(net "P5E_CPU0_P2_TX_C_DN<0>")
		)
		(pad "2" smd rect
			(at 0.2667 0 180)
			(size 0.3048 0.381)
			(layers "F.Cu" "F.Mask" "F.Paste")
			(net "P5E_CPU0_P2_TX_DN<0>")
		)
	)
	(footprint ""
		(layer "F.Cu")
		(at 118.718584 -60.900056)
		(property "Reference" "R1736"
			(at 0 0 0)
			(layer "F.SilkS")
			(hide yes)
			(effects
				(font
					(size 1.27 1.27)
				)
			)
		)
		(property "Value" ""
			(at 0 0 0)
			(layer "F.Fab")
			(effects
				(font
					(size 1.27 1.27)
				)
			)
		)
		(duplicate_pad_numbers_are_jumpers no)
		(fp_line
			(start -0.7874 -0.4064)
			(end 0.7874 -0.4064)
			(stroke
				(width 0.1524)
				(type default)
			)
			(layer "F.SilkS")
		)
		(fp_line
			(start -0.7874 0.4064)
			(end -0.7874 -0.4064)
			(stroke
				(width 0.1524)
				(type default)
			)
			(layer "F.SilkS")
		)
		(fp_line
			(start 0.7874 -0.4064)
			(end 0.7874 0.4064)
			(stroke
				(width 0.1524)
				(type default)
			)
			(layer "F.SilkS")
		)
		(fp_line
			(start 0.7874 0.4064)
			(end -0.7874 0.4064)
			(stroke
				(width 0.1524)
				(type default)
			)
			(layer "F.SilkS")
		)
		(fp_line
			(start -0.67945 -0.305054)
			(end -0.12065 -0.305054)
			(stroke
				(width 0.1)
				(type default)
			)
			(layer "F.Fab")
		)
		(fp_line
			(start -0.67945 0.3048)
			(end -0.67945 -0.305054)
			(stroke
				(width 0.1)
				(type default)
			)
			(layer "F.Fab")
		)
		(fp_line
			(start -0.12065 -0.305054)
			(end -0.12065 -0.2794)
			(stroke
				(width 0.1)
				(type default)
			)
			(layer "F.Fab")
		)
		(fp_line
			(start -0.12065 -0.2794)
			(end 0.12065 -0.2794)
			(stroke
				(width 0.1)
				(type default)
			)
			(layer "F.Fab")
		)
		(fp_line
			(start -0.12065 0.2794)
			(end -0.12065 0.3048)
			(stroke
				(width 0.1)
				(type default)
			)
			(layer "F.Fab")
		)
		(fp_line
			(start -0.12065 0.3048)
			(end -0.67945 0.3048)
			(stroke
				(width 0.1)
				(type default)
			)
			(layer "F.Fab")
		)
		(fp_line
			(start 0.120396 0.2794)
			(end -0.12065 0.2794)
			(stroke
				(width 0.1)
				(type default)
			)
			(layer "F.Fab")
		)
		(fp_line
			(start 0.120396 0.3048)
			(end 0.120396 0.2794)
			(stroke
				(width 0.1)
				(type default)
			)
			(layer "F.Fab")
		)
		(fp_line
			(start 0.12065 -0.3048)
			(end 0.67945 -0.3048)
			(stroke
				(width 0.1)
				(type default)
			)
			(layer "F.Fab")
		)
		(fp_line
			(start 0.12065 -0.2794)
			(end 0.12065 -0.3048)
			(stroke
				(width 0.1)
				(type default)
			)
			(layer "F.Fab")
		)
		(fp_line
			(start 0.67945 -0.3048)
			(end 0.67945 0.3048)
			(stroke
				(width 0.1)
				(type default)
			)
			(layer "F.Fab")
		)
		(fp_line
			(start 0.67945 0.3048)
			(end 0.120396 0.3048)
			(stroke
				(width 0.1)
				(type default)
			)
			(layer "F.Fab")
		)
		(pad "1" smd circle
			(at -0.40005 0)
			(size 0 0)
			(layers "F.Cu" "F.Mask" "F.Paste")
			(net "JTAG_SCM_MUX_R_TCK")
		)
		(pad "2" smd circle
			(at 0.40005 0)
			(size 0 0)
			(layers "F.Cu" "F.Mask" "F.Paste")
			(net "JTAG_SCM_MUX_TCK")
		)
	)
)
